# T6G (Grand Teton) — schematic netlist excerpt (pin names and nets, part order shuffled) for the footprints in the layout excerpt that follows; sources: Cadence DE-HDL packaged netlist, KiCad conversion of 04192023_DAF0TMB3IC0_F0TG_MB_C_brd_V02_OCP.brd

R8116  Q_RES  0 5% EMPTY  pkg 0402LF  page 207 : A = PVDD11_S3_P0_OCP_N ; B = PVDD11_S3_P0_OCP_N_R
C6669  Q_CAP_DIFFBUS  DIFF BUS_0.22UF 6.3V 20% X6S  pkg C0201  page 330 : \1\ = P5E_CPU1_P1_TX_BUF_C_DP<4> ; \2\ = P5E_CPU1_P1_TX_BUF_DP<4>
R2915  Q_RES  4.7K 5% CHIP  pkg 0402LF  page 130 : A = BMC_MONITER_R ; B = GND

(kicad_pcb
	(version 20260206)
	(generator "pcbnew")
	(generator_version "10.0")
	(general
		(thickness 1.6)
		(legacy_teardrops no)
	)
	(paper "A4")
	(title_block
		(title "04192023_DAF0TMB3IC0_F0TG_MB_C_brd_V02_OCP.brd")
		(comment 1 "Grand Teton / footprints 5610-5612 of 8354")
	)
	(layers
		(0 "F.Cu" signal "TOP")
		(4 "In1.Cu" signal "GND")
		(6 "In2.Cu" signal "IN1")
		(8 "In3.Cu" signal "GND1")
		(10 "In4.Cu" signal "IN2")
		(12 "In5.Cu" signal "GND2")
		(14 "In6.Cu" signal "IN3")
		(16 "In7.Cu" signal "GND3")
		(18 "In8.Cu" signal "VCC")
		(20 "In9.Cu" signal "VCC1")
		(22 "In10.Cu" signal "GND4")
		(24 "In11.Cu" signal "IN4")
		(26 "In12.Cu" signal "GND5")
		(28 "In13.Cu" signal "IN5")
		(30 "In14.Cu" signal "GND6")
		(32 "In15.Cu" signal "IN6")
		(34 "In16.Cu" signal "GND7")
		(2 "B.Cu" signal "BOTTOM")
		(9 "F.Adhes" user "F.Adhesive")
		(11 "B.Adhes" user "B.Adhesive")
		(13 "F.Paste" user "Package Geometry/Pastemask Top")
		(15 "B.Paste" user "Package Geometry/Pastemask Bottom")
		(5 "F.SilkS" user "Ref Des/Silkscreen Top")
		(7 "B.SilkS" user "Ref Des/Silkscreen Bottom")
		(1 "F.Mask" user "Board Geometry/Soldermask Top")
		(3 "B.Mask" user "Board Geometry/Soldermask Bottom")
		(17 "Dwgs.User" user "User.Drawings")
		(19 "Cmts.User" user "User.Comments")
		(21 "Eco1.User" user "User.Eco1")
		(23 "Eco2.User" user "User.Eco2")
		(25 "Edge.Cuts" user "Board Geometry/Outline")
		(27 "Margin" user)
		(31 "F.CrtYd" user "Package Geometry/Place Bound Top")
		(29 "B.CrtYd" user "Package Geometry/Place Bound Bottom")
		(35 "F.Fab" user "Ref Des/Assembly Top")
		(33 "B.Fab" user "Ref Des/Assembly Bottom")
	)
	(footprint ""
		(layer "B.Cu")
		(at 62.467744 -408.517344 90)
		(property "Reference" "C6669"
			(at 0 0 90)
			(layer "B.SilkS")
			(hide yes)
			(effects
				(font
					(size 1.27 1.27)
				)
				(justify mirror)
			)
		)
		(property "Value" ""
			(at 0 0 90)
			(layer "B.Fab")
			(effects
				(font
					(size 1.27 1.27)
				)
				(justify mirror)
			)
		)
		(duplicate_pad_numbers_are_jumpers no)
		(fp_line
			(start 0.299974 -0.150114)
			(end -0.299974 -0.150114)
			(stroke
				(width 0.1)
				(type default)
			)
			(layer "B.Fab")
		)
		(fp_line
			(start -0.299974 -0.150114)
			(end -0.299974 0.150114)
			(stroke
				(width 0.1)
				(type default)
			)
			(layer "B.Fab")
		)
		(fp_line
			(start 0.299974 0.150114)
			(end 0.299974 -0.150114)
			(stroke
				(width 0.1)
				(type default)
			)
			(layer "B.Fab")
		)
		(fp_line
			(start -0.299974 0.150114)
			(end 0.299974 0.150114)
			(stroke
				(width 0.1)
				(type default)
			)
			(layer "B.Fab")
		)
		(pad "1" smd rect
			(at 0.2667 0 270)
			(size 0.3048 0.381)
			(layers "B.Cu" "B.Mask" "B.Paste")
			(net "P5E_CPU1_P1_TX_BUF_C_DP<4>")
		)
		(pad "2" smd rect
			(at -0.2667 0 270)
			(size 0.3048 0.381)
			(layers "B.Cu" "B.Mask" "B.Paste")
			(net "P5E_CPU1_P1_TX_BUF_DP<4>")
		)
	)
	(footprint ""
		(layer "B.Cu")
		(at 172.456094 -413.776668)
		(property "Reference" "R2915"
			(at 0 0 0)
			(layer "B.SilkS")
			(hide yes)
			(effects
				(font
					(size 1.27 1.27)
				)
				(justify mirror)
			)
		)
		(property "Value" ""
			(at 0 0 0)
			(layer "B.Fab")
			(effects
				(font
					(size 1.27 1.27)
				)
				(justify mirror)
			)
		)
		(duplicate_pad_numbers_are_jumpers no)
		(fp_line
			(start -0.7874 -0.4064)
			(end -0.7874 0.4064)
			(stroke
				(width 0.1524)
				(type default)
			)
			(layer "B.SilkS")
		)
		(fp_line
			(start -0.7874 0.4064)
			(end 0.7874 0.4064)
			(stroke
				(width 0.1524)
				(type default)
			)
			(layer "B.SilkS")
		)
		(fp_line
			(start 0.7874 -0.4064)
			(end -0.7874 -0.4064)
			(stroke
				(width 0.1524)
				(type default)
			)
			(layer "B.SilkS")
		)
		(fp_line
			(start 0.7874 0.4064)
			(end 0.7874 -0.4064)
			(stroke
				(width 0.1524)
				(type default)
			)
			(layer "B.SilkS")
		)
		(fp_line
			(start -0.67945 -0.3048)
			(end -0.67945 0.3048)
			(stroke
				(width 0.1)
				(type default)
			)
			(layer "B.Fab")
		)
		(fp_line
			(start -0.67945 0.3048)
			(end -0.120396 0.3048)
			(stroke
				(width 0.1)
				(type default)
			)
			(layer "B.Fab")
		)
		(fp_line
			(start -0.12065 -0.3048)
			(end -0.67945 -0.3048)
			(stroke
				(width 0.1)
				(type default)
			)
			(layer "B.Fab")
		)
		(fp_line
			(start -0.12065 -0.2794)
			(end -0.12065 -0.3048)
			(stroke
				(width 0.1)
				(type default)
			)
			(layer "B.Fab")
		)
		(fp_line
			(start -0.120396 0.2794)
			(end 0.12065 0.2794)
			(stroke
				(width 0.1)
				(type default)
			)
			(layer "B.Fab")
		)
		(fp_line
			(start -0.120396 0.3048)
			(end -0.120396 0.2794)
			(stroke
				(width 0.1)
				(type default)
			)
			(layer "B.Fab")
		)
		(fp_line
			(start 0.12065 -0.305054)
			(end 0.12065 -0.2794)
			(stroke
				(width 0.1)
				(type default)
			)
			(layer "B.Fab")
		)
		(fp_line
			(start 0.12065 -0.2794)
			(end -0.12065 -0.2794)
			(stroke
				(width 0.1)
				(type default)
			)
			(layer "B.Fab")
		)
		(fp_line
			(start 0.12065 0.2794)
			(end 0.12065 0.3048)
			(stroke
				(width 0.1)
				(type default)
			)
			(layer "B.Fab")
		)
		(fp_line
			(start 0.12065 0.3048)
			(end 0.67945 0.3048)
			(stroke
				(width 0.1)
				(type default)
			)
			(layer "B.Fab")
		)
		(fp_line
			(start 0.67945 -0.305054)
			(end 0.12065 -0.305054)
			(stroke
				(width 0.1)
				(type default)
			)
			(layer "B.Fab")
		)
		(fp_line
			(start 0.67945 0.3048)
			(end 0.67945 -0.305054)
			(stroke
				(width 0.1)
				(type default)
			)
			(layer "B.Fab")
		)
		(pad "1" smd circle
			(at 0.40005 0 180)
			(size 0 0)
			(layers "B.Cu" "B.Mask" "B.Paste")
			(net "BMC_MONITER_R")
		)
		(pad "2" smd circle
			(at -0.40005 0 180)
			(size 0 0)
			(layers "B.Cu" "B.Mask" "B.Paste")
			(net "GND")
		)
	)
	(footprint ""
		(layer "B.Cu")
		(at 423.63009 -359.84434)
		(property "Reference" "R8116"
			(at 0 0 0)
			(layer "B.SilkS")
			(hide yes)
			(effects
				(font
					(size 1.27 1.27)
				)
				(justify mirror)
			)
		)
		(property "Value" ""
			(at 0 0 0)
			(layer "B.Fab")
			(effects
				(font
					(size 1.27 1.27)
				)
				(justify mirror)
			)
		)
		(duplicate_pad_numbers_are_jumpers no)
		(fp_line
			(start -0.7874 -0.4064)
			(end -0.7874 0.4064)
			(stroke
				(width 0.1524)
				(type default)
			)
			(layer "B.SilkS")
		)
		(fp_line
			(start -0.7874 0.4064)
			(end 0.7874 0.4064)
			(stroke
				(width 0.1524)
				(type default)
			)
			(layer "B.SilkS")
		)
		(fp_line
			(start 0.7874 -0.4064)
			(end -0.7874 -0.4064)
			(stroke
				(width 0.1524)
				(type default)
			)
			(layer "B.SilkS")
		)
		(fp_line
			(start 0.7874 0.4064)
			(end 0.7874 -0.4064)
			(stroke
				(width 0.1524)
				(type default)
			)
			(layer "B.SilkS")
		)
		(fp_line
			(start -0.67945 -0.3048)
			(end -0.67945 0.3048)
			(stroke
				(width 0.1)
				(type default)
			)
			(layer "B.Fab")
		)
		(fp_line
			(start -0.67945 0.3048)
			(end -0.120396 0.3048)
			(stroke
				(width 0.1)
				(type default)
			)
			(layer "B.Fab")
		)
		(fp_line
			(start -0.12065 -0.3048)
			(end -0.67945 -0.3048)
			(stroke
				(width 0.1)
				(type default)
			)
			(layer "B.Fab")
		)
		(fp_line
			(start -0.12065 -0.2794)
			(end -0.12065 -0.3048)
			(stroke
				(width 0.1)
				(type default)
			)
			(layer "B.Fab")
		)
		(fp_line
			(start -0.120396 0.2794)
			(end 0.12065 0.2794)
			(stroke
				(width 0.1)
				(type default)
			)
			(layer "B.Fab")
		)
		(fp_line
			(start -0.120396 0.3048)
			(end -0.120396 0.2794)
			(stroke
				(width 0.1)
				(type default)
			)
			(layer "B.Fab")
		)
		(fp_line
			(start 0.12065 -0.305054)
			(end 0.12065 -0.2794)
			(stroke
				(width 0.1)
				(type default)
			)
			(layer "B.Fab")
		)
		(fp_line
			(start 0.12065 -0.2794)
			(end -0.12065 -0.2794)
			(stroke
				(width 0.1)
				(type default)
			)
			(layer "B.Fab")
		)
		(fp_line
			(start 0.12065 0.2794)
			(end 0.12065 0.3048)
			(stroke
				(width 0.1)
				(type default)
			)
			(layer "B.Fab")
		)
		(fp_line
			(start 0.12065 0.3048)
			(end 0.67945 0.3048)
			(stroke
				(width 0.1)
				(type default)
			)
			(layer "B.Fab")
		)
		(fp_line
			(start 0.67945 -0.305054)
			(end 0.12065 -0.305054)
			(stroke
				(width 0.1)
				(type default)
			)
			(layer "B.Fab")
		)
		(fp_line
			(start 0.67945 0.3048)
			(end 0.67945 -0.305054)
			(stroke
				(width 0.1)
				(type default)
			)
			(layer "B.Fab")
		)
		(pad "1" smd circle
			(at 0.40005 0 180)
			(size 0 0)
			(layers "B.Cu" "B.Mask" "B.Paste")
			(net "PVDD11_S3_P0_OCP_N")
		)
		(pad "2" smd circle
			(at -0.40005 0 180)
			(size 0 0)
			(layers "B.Cu" "B.Mask" "B.Paste")
			(net "PVDD11_S3_P0_OCP_N_R")
		)
	)
)
